(kicad_pcb
	(version 20260206)
	(generator "pcbnew")
	(generator_version "10.0")
	(general
		(thickness 1.6)
		(legacy_teardrops no)
	)
	(paper "A4")
	(title_block
		(title "pdpb — Lightning_PDPB_BRD.brd")
		(comment 1 "Lightning (Wiwynn / Facebook NVMe JBOF) / footprints 457-463 of 1140")
	)
	(layers
		(0 "F.Cu" signal "TOP")
		(4 "In1.Cu" signal "L2GND")
		(6 "In2.Cu" signal "L3")
		(8 "In3.Cu" signal "L4VCC")
		(10 "In4.Cu" signal "L5VCC")
		(12 "In5.Cu" signal "L6")
		(14 "In6.Cu" signal "L7GND")
		(2 "B.Cu" signal "BOTTOM")
		(9 "F.Adhes" user "F.Adhesive")
		(11 "B.Adhes" user "B.Adhesive")
		(13 "F.Paste" user "Package Geometry/Pastemask Top")
		(15 "B.Paste" user "Package Geometry/Pastemask Bottom")
		(5 "F.SilkS" user "Ref Des/Silkscreen Top")
		(7 "B.SilkS" user "Ref Des/Silkscreen Bottom")
		(1 "F.Mask" user "Board Geometry/Soldermask Top")
		(3 "B.Mask" user "Board Geometry/Soldermask Bottom")
		(17 "Dwgs.User" user "User.Drawings")
		(19 "Cmts.User" user "User.Comments")
		(21 "Eco1.User" user "User.Eco1")
		(23 "Eco2.User" user "User.Eco2")
		(25 "Edge.Cuts" user "Board Geometry/Outline")
		(27 "Margin" user)
		(31 "F.CrtYd" user "Package Geometry/Place Bound Top")
		(29 "B.CrtYd" user "Package Geometry/Place Bound Bottom")
		(35 "F.Fab" user "Ref Des/Assembly Top")
		(33 "B.Fab" user "Ref Des/Assembly Bottom")
	)
	(footprint ""
		(layer "F.Cu")
		(at 80.645 -143.256 180)
		(property "Reference" "SR1152"
			(at 0 0 180)
			(layer "F.SilkS")
			(hide yes)
			(effects
				(font
					(size 1.27 1.27)
				)
			)
		)
		(property "Value" "4K7R2F-GP"
			(at 0.064008 -3.993896 180)
			(unlocked yes)
			(layer "F.Fab")
			(hide yes)
			(effects
				(font
					(size 1.016 1.016)
					(thickness 0.1524)
				)
			)
		)
		(property "Device Type" "R402H16"
			(at 0.064008 -5.517896 180)
			(unlocked yes)
			(layer "F.Fab")
			(hide yes)
			(effects
				(font
					(size 1.016 1.016)
					(thickness 0.1524)
				)
			)
		)
		(duplicate_pad_numbers_are_jumpers no)
		(fp_line
			(start 0.508 -0.9398)
			(end -0.508 -0.9398)
			(stroke
				(width 0.1524)
				(type default)
			)
			(layer "F.SilkS")
		)
		(fp_line
			(start -0.508 -0.9398)
			(end -0.508 0.9398)
			(stroke
				(width 0.1524)
				(type default)
			)
			(layer "F.SilkS")
		)
		(fp_rect
			(start -0.508 0.9398)
			(end 0.508 -0.9398)
			(stroke
				(width 0)
				(type default)
			)
			(fill no)
			(layer "F.CrtYd")
		)
		(fp_rect
			(start -0.508 0.9398)
			(end 0.508 -0.9398)
			(stroke
				(width 0)
				(type default)
			)
			(fill no)
			(layer "F.Fab")
		)
		(pad "1" smd custom
			(at 0 -0.4445 180)
			(size 0.1397 0.1397)
			(layers "F.Cu" "F.Mask" "F.Paste")
			(net "P3V3")
			(options
				(clearance outline)
				(anchor circle)
			)
			(primitives
				(gr_poly
					(pts
						(arc
							(start -0.1778 -0.2794)
							(mid -0.249642 -0.249642)
							(end -0.2794 -0.1778)
						)
						(arc
							(start -0.2794 0.1778)
							(mid -0.249642 0.249642)
							(end -0.1778 0.2794)
						)
						(arc
							(start 0.1778 0.2794)
							(mid 0.249642 0.249642)
							(end 0.2794 0.1778)
						)
						(arc
							(start 0.2794 -0.1778)
							(mid 0.249642 -0.249642)
							(end 0.1778 -0.2794)
						)
					)
					(width 0)
					(fill yes)
				)
			)
		)
		(pad "2" smd custom
			(at 0 0.4445 180)
			(size 0.1397 0.1397)
			(layers "F.Cu" "F.Mask" "F.Paste")
			(net "I2C_SW_EU16_ADDRESS_A2")
			(options
				(clearance outline)
				(anchor circle)
			)
			(primitives
				(gr_poly
					(pts
						(arc
							(start -0.1778 -0.2794)
							(mid -0.249642 -0.249642)
							(end -0.2794 -0.1778)
						)
						(arc
							(start -0.2794 0.1778)
							(mid -0.249642 0.249642)
							(end -0.1778 0.2794)
						)
						(arc
							(start 0.1778 0.2794)
							(mid 0.249642 0.249642)
							(end 0.2794 0.1778)
						)
						(arc
							(start 0.2794 -0.1778)
							(mid 0.249642 -0.249642)
							(end 0.1778 -0.2794)
						)
					)
					(width 0)
					(fill yes)
				)
			)
		)
	)
	(footprint ""
		(layer "F.Cu")
		(at 81.153 -354.076 180)
		(property "Reference" "PR9047"
			(at 0 0 180)
			(layer "F.SilkS")
			(hide yes)
			(effects
				(font
					(size 1.27 1.27)
				)
			)
		)
		(property "Value" "0R2J-2-GP"
			(at 0.064008 -3.993896 180)
			(unlocked yes)
			(layer "F.Fab")
			(hide yes)
			(effects
				(font
					(size 1.016 1.016)
					(thickness 0.1524)
				)
			)
		)
		(property "Device Type" "R402H16"
			(at 0.064008 -5.517896 180)
			(unlocked yes)
			(layer "F.Fab")
			(hide yes)
			(effects
				(font
					(size 1.016 1.016)
					(thickness 0.1524)
				)
			)
		)
		(duplicate_pad_numbers_are_jumpers no)
		(fp_line
			(start 0.508 -0.9398)
			(end -0.508 -0.9398)
			(stroke
				(width 0.1524)
				(type default)
			)
			(layer "F.SilkS")
		)
		(fp_line
			(start -0.508 -0.9398)
			(end -0.508 0.9398)
			(stroke
				(width 0.1524)
				(type default)
			)
			(layer "F.SilkS")
		)
		(fp_rect
			(start -0.508 0.9398)
			(end 0.508 -0.9398)
			(stroke
				(width 0)
				(type default)
			)
			(fill no)
			(layer "F.CrtYd")
		)
		(fp_rect
			(start -0.508 0.9398)
			(end 0.508 -0.9398)
			(stroke
				(width 0)
				(type default)
			)
			(fill no)
			(layer "F.Fab")
		)
		(pad "1" smd custom
			(at 0 -0.4445 180)
			(size 0.1397 0.1397)
			(layers "F.Cu" "F.Mask" "F.Paste")
			(net "I2C_MUX_RESET")
			(options
				(clearance outline)
				(anchor circle)
			)
			(primitives
				(gr_poly
					(pts
						(arc
							(start -0.1778 -0.2794)
							(mid -0.249642 -0.249642)
							(end -0.2794 -0.1778)
						)
						(arc
							(start -0.2794 0.1778)
							(mid -0.249642 0.249642)
							(end -0.1778 0.2794)
						)
						(arc
							(start 0.1778 0.2794)
							(mid 0.249642 0.249642)
							(end 0.2794 0.1778)
						)
						(arc
							(start 0.2794 -0.1778)
							(mid 0.249642 -0.249642)
							(end 0.1778 -0.2794)
						)
					)
					(width 0)
					(fill yes)
				)
			)
		)
		(pad "2" smd custom
			(at 0 0.4445 180)
			(size 0.1397 0.1397)
			(layers "F.Cu" "F.Mask" "F.Paste")
			(net "I2C_MUX_RESET_R_EU17")
			(options
				(clearance outline)
				(anchor circle)
			)
			(primitives
				(gr_poly
					(pts
						(arc
							(start -0.1778 -0.2794)
							(mid -0.249642 -0.249642)
							(end -0.2794 -0.1778)
						)
						(arc
							(start -0.2794 0.1778)
							(mid -0.249642 0.249642)
							(end -0.1778 0.2794)
						)
						(arc
							(start 0.1778 0.2794)
							(mid 0.249642 0.249642)
							(end 0.2794 0.1778)
						)
						(arc
							(start 0.2794 -0.1778)
							(mid 0.249642 -0.249642)
							(end 0.1778 -0.2794)
						)
					)
					(width 0)
					(fill yes)
				)
			)
		)
	)
	(footprint ""
		(layer "F.Cu")
		(at 84.455 -207.01 90)
		(property "Reference" "R423"
			(at 0 0 90)
			(layer "F.SilkS")
			(hide yes)
			(effects
				(font
					(size 1.27 1.27)
				)
			)
		)
		(property "Value" "0R2J-2-GP"
			(at 0.064008 -3.993896 90)
			(unlocked yes)
			(layer "F.Fab")
			(hide yes)
			(effects
				(font
					(size 1.016 1.016)
					(thickness 0.1524)
				)
			)
		)
		(property "Device Type" "R402H16"
			(at 0.064008 -5.517896 90)
			(unlocked yes)
			(layer "F.Fab")
			(hide yes)
			(effects
				(font
					(size 1.016 1.016)
					(thickness 0.1524)
				)
			)
		)
		(duplicate_pad_numbers_are_jumpers no)
		(fp_line
			(start 0.508 -0.9398)
			(end -0.508 -0.9398)
			(stroke
				(width 0.1524)
				(type default)
			)
			(layer "F.SilkS")
		)
		(fp_line
			(start -0.508 -0.9398)
			(end -0.508 0.9398)
			(stroke
				(width 0.1524)
				(type default)
			)
			(layer "F.SilkS")
		)
		(fp_rect
			(start -0.508 0.9398)
			(end 0.508 -0.9398)
			(stroke
				(width 0)
				(type default)
			)
			(fill no)
			(layer "F.CrtYd")
		)
		(fp_rect
			(start -0.508 0.9398)
			(end 0.508 -0.9398)
			(stroke
				(width 0)
				(type default)
			)
			(fill no)
			(layer "F.Fab")
		)
		(pad "1" smd custom
			(at 0 -0.4445 90)
			(size 0.1397 0.1397)
			(layers "F.Cu" "F.Mask" "F.Paste")
			(net "BMC_I2C_SDA_BUF_8")
			(options
				(clearance outline)
				(anchor circle)
			)
			(primitives
				(gr_poly
					(pts
						(arc
							(start -0.1778 -0.2794)
							(mid -0.249642 -0.249642)
							(end -0.2794 -0.1778)
						)
						(arc
							(start -0.2794 0.1778)
							(mid -0.249642 0.249642)
							(end -0.1778 0.2794)
						)
						(arc
							(start 0.1778 0.2794)
							(mid 0.249642 0.249642)
							(end 0.2794 0.1778)
						)
						(arc
							(start 0.2794 -0.1778)
							(mid 0.249642 -0.249642)
							(end 0.1778 -0.2794)
						)
					)
					(width 0)
					(fill yes)
				)
			)
		)
		(pad "2" smd custom
			(at 0 0.4445 90)
			(size 0.1397 0.1397)
			(layers "F.Cu" "F.Mask" "F.Paste")
			(net "I2C_SDA_BUF_8_EU3_R")
			(options
				(clearance outline)
				(anchor circle)
			)
			(primitives
				(gr_poly
					(pts
						(arc
							(start -0.1778 -0.2794)
							(mid -0.249642 -0.249642)
							(end -0.2794 -0.1778)
						)
						(arc
							(start -0.2794 0.1778)
							(mid -0.249642 0.249642)
							(end -0.1778 0.2794)
						)
						(arc
							(start 0.1778 0.2794)
							(mid 0.249642 0.249642)
							(end 0.2794 0.1778)
						)
						(arc
							(start 0.2794 -0.1778)
							(mid 0.249642 -0.249642)
							(end 0.1778 -0.2794)
						)
					)
					(width 0)
					(fill yes)
				)
			)
		)
	)
	(footprint ""
		(layer "F.Cu")
		(at 243.586 -424.18)
		(property "Reference" "R369"
			(at 0 0 0)
			(layer "F.SilkS")
			(hide yes)
			(effects
				(font
					(size 1.27 1.27)
				)
			)
		)
		(property "Value" "4K7R2J-2-GP"
			(at 0.064008 -3.993896 0)
			(unlocked yes)
			(layer "F.Fab")
			(hide yes)
			(effects
				(font
					(size 1.016 1.016)
					(thickness 0.1524)
				)
			)
		)
		(property "Device Type" "R402H16"
			(at 0.064008 -5.517896 0)
			(unlocked yes)
			(layer "F.Fab")
			(hide yes)
			(effects
				(font
					(size 1.016 1.016)
					(thickness 0.1524)
				)
			)
		)
		(duplicate_pad_numbers_are_jumpers no)
		(fp_line
			(start -0.508 -0.9398)
			(end -0.508 0.9398)
			(stroke
				(width 0.1524)
				(type default)
			)
			(layer "F.SilkS")
		)
		(fp_line
			(start 0.508 -0.9398)
			(end -0.508 -0.9398)
			(stroke
				(width 0.1524)
				(type default)
			)
			(layer "F.SilkS")
		)
		(fp_rect
			(start -0.508 0.9398)
			(end 0.508 -0.9398)
			(stroke
				(width 0)
				(type default)
			)
			(fill no)
			(layer "F.CrtYd")
		)
		(fp_rect
			(start -0.508 0.9398)
			(end 0.508 -0.9398)
			(stroke
				(width 0)
				(type default)
			)
			(fill no)
			(layer "F.Fab")
		)
		(pad "1" smd custom
			(at 0 -0.4445)
			(size 0.1397 0.1397)
			(layers "F.Cu" "F.Mask" "F.Paste")
			(net "P3V3")
			(options
				(clearance outline)
				(anchor circle)
			)
			(primitives
				(gr_poly
					(pts
						(arc
							(start -0.1778 -0.2794)
							(mid -0.249642 -0.249642)
							(end -0.2794 -0.1778)
						)
						(arc
							(start -0.2794 0.1778)
							(mid -0.249642 0.249642)
							(end -0.1778 0.2794)
						)
						(arc
							(start 0.1778 0.2794)
							(mid 0.249642 0.249642)
							(end 0.2794 0.1778)
						)
						(arc
							(start 0.2794 -0.1778)
							(mid 0.249642 -0.249642)
							(end 0.1778 -0.2794)
						)
					)
					(width 0)
					(fill yes)
				)
			)
		)
		(pad "2" smd custom
			(at 0 0.4445)
			(size 0.1397 0.1397)
			(layers "F.Cu" "F.Mask" "F.Paste")
			(net "I2C_C_SCL")
			(options
				(clearance outline)
				(anchor circle)
			)
			(primitives
				(gr_poly
					(pts
						(arc
							(start -0.1778 -0.2794)
							(mid -0.249642 -0.249642)
							(end -0.2794 -0.1778)
						)
						(arc
							(start -0.2794 0.1778)
							(mid -0.249642 0.249642)
							(end -0.1778 0.2794)
						)
						(arc
							(start 0.1778 0.2794)
							(mid 0.249642 0.249642)
							(end 0.2794 0.1778)
						)
						(arc
							(start 0.2794 -0.1778)
							(mid 0.249642 -0.249642)
							(end 0.1778 -0.2794)
						)
					)
					(width 0)
					(fill yes)
				)
			)
		)
	)
	(footprint ""
		(layer "F.Cu")
		(at 84.455 -94.742 -90)
		(property "Reference" "R9122"
			(at 0 0 270)
			(layer "F.SilkS")
			(hide yes)
			(effects
				(font
					(size 1.27 1.27)
				)
			)
		)
		(property "Value" "4K7R2F-GP"
			(at 0.064008 -3.993896 270)
			(unlocked yes)
			(layer "F.Fab")
			(hide yes)
			(effects
				(font
					(size 1.016 1.016)
					(thickness 0.1524)
				)
			)
		)
		(property "Device Type" "R402H16"
			(at 0.064008 -5.517896 270)
			(unlocked yes)
			(layer "F.Fab")
			(hide yes)
			(effects
				(font
					(size 1.016 1.016)
					(thickness 0.1524)
				)
			)
		)
		(duplicate_pad_numbers_are_jumpers no)
		(fp_line
			(start -0.508 -0.9398)
			(end -0.508 0.9398)
			(stroke
				(width 0.1524)
				(type default)
			)
			(layer "F.SilkS")
		)
		(fp_line
			(start 0.508 -0.9398)
			(end -0.508 -0.9398)
			(stroke
				(width 0.1524)
				(type default)
			)
			(layer "F.SilkS")
		)
		(fp_rect
			(start -0.508 0.9398)
			(end 0.508 -0.9398)
			(stroke
				(width 0)
				(type default)
			)
			(fill no)
			(layer "F.CrtYd")
		)
		(fp_rect
			(start -0.508 0.9398)
			(end 0.508 -0.9398)
			(stroke
				(width 0)
				(type default)
			)
			(fill no)
			(layer "F.Fab")
		)
		(pad "1" smd custom
			(at 0 -0.4445 270)
			(size 0.1397 0.1397)
			(layers "F.Cu" "F.Mask" "F.Paste")
			(net "CLK_BUF_EU4_SMB_A1_TRI")
			(options
				(clearance outline)
				(anchor circle)
			)
			(primitives
				(gr_poly
					(pts
						(arc
							(start -0.1778 -0.2794)
							(mid -0.249642 -0.249642)
							(end -0.2794 -0.1778)
						)
						(arc
							(start -0.2794 0.1778)
							(mid -0.249642 0.249642)
							(end -0.1778 0.2794)
						)
						(arc
							(start 0.1778 0.2794)
							(mid 0.249642 0.249642)
							(end 0.2794 0.1778)
						)
						(arc
							(start 0.2794 -0.1778)
							(mid 0.249642 -0.249642)
							(end 0.1778 -0.2794)
						)
					)
					(width 0)
					(fill yes)
				)
			)
		)
		(pad "2" smd custom
			(at 0 0.4445 270)
			(size 0.1397 0.1397)
			(layers "F.Cu" "F.Mask" "F.Paste")
			(net "GND")
			(options
				(clearance outline)
				(anchor circle)
			)
			(primitives
				(gr_poly
					(pts
						(arc
							(start -0.1778 -0.2794)
							(mid -0.249642 -0.249642)
							(end -0.2794 -0.1778)
						)
						(arc
							(start -0.2794 0.1778)
							(mid -0.249642 0.249642)
							(end -0.1778 0.2794)
						)
						(arc
							(start 0.1778 0.2794)
							(mid 0.249642 0.249642)
							(end 0.2794 0.1778)
						)
						(arc
							(start 0.2794 -0.1778)
							(mid 0.249642 -0.249642)
							(end 0.1778 -0.2794)
						)
					)
					(width 0)
					(fill yes)
				)
			)
		)
	)
	(footprint ""
		(layer "F.Cu")
		(at 203.454 -458.978 90)
		(property "Reference" "R319"
			(at 0 0 90)
			(layer "F.SilkS")
			(hide yes)
			(effects
				(font
					(size 1.27 1.27)
				)
			)
		)
		(property "Value" "0R2J-2-GP"
			(at 0.064008 -3.993896 90)
			(unlocked yes)
			(layer "F.Fab")
			(hide yes)
			(effects
				(font
					(size 1.016 1.016)
					(thickness 0.1524)
				)
			)
		)
		(property "Device Type" "R402H16"
			(at 0.064008 -5.517896 90)
			(unlocked yes)
			(layer "F.Fab")
			(hide yes)
			(effects
				(font
					(size 1.016 1.016)
					(thickness 0.1524)
				)
			)
		)
		(duplicate_pad_numbers_are_jumpers no)
		(fp_line
			(start 0.508 -0.9398)
			(end -0.508 -0.9398)
			(stroke
				(width 0.1524)
				(type default)
			)
			(layer "F.SilkS")
		)
		(fp_line
			(start -0.508 -0.9398)
			(end -0.508 0.9398)
			(stroke
				(width 0.1524)
				(type default)
			)
			(layer "F.SilkS")
		)
		(fp_rect
			(start -0.508 0.9398)
			(end 0.508 -0.9398)
			(stroke
				(width 0)
				(type default)
			)
			(fill no)
			(layer "F.CrtYd")
		)
		(fp_rect
			(start -0.508 0.9398)
			(end 0.508 -0.9398)
			(stroke
				(width 0)
				(type default)
			)
			(fill no)
			(layer "F.Fab")
		)
		(pad "1" smd custom
			(at 0 -0.4445 90)
			(size 0.1397 0.1397)
			(layers "F.Cu" "F.Mask" "F.Paste")
			(net "I2C_B_SCL")
			(options
				(clearance outline)
				(anchor circle)
			)
			(primitives
				(gr_poly
					(pts
						(arc
							(start -0.1778 -0.2794)
							(mid -0.249642 -0.249642)
							(end -0.2794 -0.1778)
						)
						(arc
							(start -0.2794 0.1778)
							(mid -0.249642 0.249642)
							(end -0.1778 0.2794)
						)
						(arc
							(start 0.1778 0.2794)
							(mid 0.249642 0.249642)
							(end 0.2794 0.1778)
						)
						(arc
							(start 0.2794 -0.1778)
							(mid 0.249642 -0.249642)
							(end 0.1778 -0.2794)
						)
					)
					(width 0)
					(fill yes)
				)
			)
		)
		(pad "2" smd custom
			(at 0 0.4445 90)
			(size 0.1397 0.1397)
			(layers "F.Cu" "F.Mask" "F.Paste")
			(net "TMP2_SCL")
			(options
				(clearance outline)
				(anchor circle)
			)
			(primitives
				(gr_poly
					(pts
						(arc
							(start -0.1778 -0.2794)
							(mid -0.249642 -0.249642)
							(end -0.2794 -0.1778)
						)
						(arc
							(start -0.2794 0.1778)
							(mid -0.249642 0.249642)
							(end -0.1778 0.2794)
						)
						(arc
							(start 0.1778 0.2794)
							(mid 0.249642 0.249642)
							(end 0.2794 0.1778)
						)
						(arc
							(start 0.2794 -0.1778)
							(mid 0.249642 -0.249642)
							(end 0.1778 -0.2794)
						)
					)
					(width 0)
					(fill yes)
				)
			)
		)
	)
	(footprint ""
		(layer "F.Cu")
		(at 82.931 -433.959 90)
		(property "Reference" "SR946"
			(at 0 0 90)
			(layer "F.SilkS")
			(hide yes)
			(effects
				(font
					(size 1.27 1.27)
				)
			)
		)
		(property "Value" "4K7R2F-GP"
			(at 0.064008 -3.993896 90)
			(unlocked yes)
			(layer "F.Fab")
			(hide yes)
			(effects
				(font
					(size 1.016 1.016)
					(thickness 0.1524)
				)
			)
		)
		(property "Device Type" "R402H16"
			(at 0.064008 -5.517896 90)
			(unlocked yes)
			(layer "F.Fab")
			(hide yes)
			(effects
				(font
					(size 1.016 1.016)
					(thickness 0.1524)
				)
			)
		)
		(duplicate_pad_numbers_are_jumpers no)
		(fp_line
			(start 0.508 -0.9398)
			(end -0.508 -0.9398)
			(stroke
				(width 0.1524)
				(type default)
			)
			(layer "F.SilkS")
		)
		(fp_line
			(start -0.508 -0.9398)
			(end -0.508 0.9398)
			(stroke
				(width 0.1524)
				(type default)
			)
			(layer "F.SilkS")
		)
		(fp_rect
			(start -0.508 0.9398)
			(end 0.508 -0.9398)
			(stroke
				(width 0)
				(type default)
			)
			(fill no)
			(layer "F.CrtYd")
		)
		(fp_rect
			(start -0.508 0.9398)
			(end 0.508 -0.9398)
			(stroke
				(width 0)
				(type default)
			)
			(fill no)
			(layer "F.Fab")
		)
		(pad "1" smd custom
			(at 0 -0.4445 90)
			(size 0.1397 0.1397)
			(layers "F.Cu" "F.Mask" "F.Paste")
			(net "VDD_DIFF_1")
			(options
				(clearance outline)
				(anchor circle)
			)
			(primitives
				(gr_poly
					(pts
						(arc
							(start -0.1778 -0.2794)
							(mid -0.249642 -0.249642)
							(end -0.2794 -0.1778)
						)
						(arc
							(start -0.2794 0.1778)
							(mid -0.249642 0.249642)
							(end -0.1778 0.2794)
						)
						(arc
							(start 0.1778 0.2794)
							(mid 0.249642 0.249642)
							(end 0.2794 0.1778)
						)
						(arc
							(start 0.2794 -0.1778)
							(mid 0.249642 -0.249642)
							(end 0.1778 -0.2794)
						)
					)
					(width 0)
					(fill yes)
				)
			)
		)
		(pad "2" smd custom
			(at 0 0.4445 90)
			(size 0.1397 0.1397)
			(layers "F.Cu" "F.Mask" "F.Paste")
			(net "P3V3_PG")
			(options
				(clearance outline)
				(anchor circle)
			)
			(primitives
				(gr_poly
					(pts
						(arc
							(start -0.1778 -0.2794)
							(mid -0.249642 -0.249642)
							(end -0.2794 -0.1778)
						)
						(arc
							(start -0.2794 0.1778)
							(mid -0.249642 0.249642)
							(end -0.1778 0.2794)
						)
						(arc
							(start 0.1778 0.2794)
							(mid 0.249642 0.249642)
							(end 0.2794 0.1778)
						)
						(arc
							(start 0.2794 -0.1778)
							(mid 0.249642 -0.249642)
							(end 0.1778 -0.2794)
						)
					)
					(width 0)
					(fill yes)
				)
			)
		)
	)
)
